(kicad_pcb
	(version 20260206)
	(generator "pcbnew")
	(generator_version "10.0")
	(general
		(thickness 1.6)
		(legacy_teardrops no)
	)
	(paper "A4")
	(title_block
		(title "04192023_DAF0TMB3IC0_F0TG_MB_C_brd_V02_OCP.brd")
		(comment 1 "Grand Teton / footprints 1791-1796 of 8354")
	)
	(layers
		(0 "F.Cu" signal "TOP")
		(4 "In1.Cu" signal "GND")
		(6 "In2.Cu" signal "IN1")
		(8 "In3.Cu" signal "GND1")
		(10 "In4.Cu" signal "IN2")
		(12 "In5.Cu" signal "GND2")
		(14 "In6.Cu" signal "IN3")
		(16 "In7.Cu" signal "GND3")
		(18 "In8.Cu" signal "VCC")
		(20 "In9.Cu" signal "VCC1")
		(22 "In10.Cu" signal "GND4")
		(24 "In11.Cu" signal "IN4")
		(26 "In12.Cu" signal "GND5")
		(28 "In13.Cu" signal "IN5")
		(30 "In14.Cu" signal "GND6")
		(32 "In15.Cu" signal "IN6")
		(34 "In16.Cu" signal "GND7")
		(2 "B.Cu" signal "BOTTOM")
		(9 "F.Adhes" user "F.Adhesive")
		(11 "B.Adhes" user "B.Adhesive")
		(13 "F.Paste" user "Package Geometry/Pastemask Top")
		(15 "B.Paste" user "Package Geometry/Pastemask Bottom")
		(5 "F.SilkS" user "Ref Des/Silkscreen Top")
		(7 "B.SilkS" user "Ref Des/Silkscreen Bottom")
		(1 "F.Mask" user "Board Geometry/Soldermask Top")
		(3 "B.Mask" user "Board Geometry/Soldermask Bottom")
		(17 "Dwgs.User" user "User.Drawings")
		(19 "Cmts.User" user "User.Comments")
		(21 "Eco1.User" user "User.Eco1")
		(23 "Eco2.User" user "User.Eco2")
		(25 "Edge.Cuts" user "Board Geometry/Outline")
		(27 "Margin" user)
		(31 "F.CrtYd" user "Package Geometry/Place Bound Top")
		(29 "B.CrtYd" user "Package Geometry/Place Bound Bottom")
		(35 "F.Fab" user "Ref Des/Assembly Top")
		(33 "B.Fab" user "Ref Des/Assembly Bottom")
	)
	(footprint ""
		(layer "F.Cu")
		(at 102.437946 -54.882034 -90)
		(property "Reference" "R6322"
			(at 0 0 270)
			(layer "F.SilkS")
			(hide yes)
			(effects
				(font
					(size 1.27 1.27)
				)
			)
		)
		(property "Value" ""
			(at 0 0 270)
			(layer "F.Fab")
			(effects
				(font
					(size 1.27 1.27)
				)
			)
		)
		(duplicate_pad_numbers_are_jumpers no)
		(fp_line
			(start -0.7874 0.4064)
			(end -0.7874 -0.4064)
			(stroke
				(width 0.1524)
				(type default)
			)
			(layer "F.SilkS")
		)
		(fp_line
			(start 0.7874 0.4064)
			(end -0.7874 0.4064)
			(stroke
				(width 0.1524)
				(type default)
			)
			(layer "F.SilkS")
		)
		(fp_line
			(start -0.7874 -0.4064)
			(end 0.7874 -0.4064)
			(stroke
				(width 0.1524)
				(type default)
			)
			(layer "F.SilkS")
		)
		(fp_line
			(start 0.7874 -0.4064)
			(end 0.7874 0.4064)
			(stroke
				(width 0.1524)
				(type default)
			)
			(layer "F.SilkS")
		)
		(fp_line
			(start -0.67945 0.3048)
			(end -0.67945 -0.305054)
			(stroke
				(width 0.1)
				(type default)
			)
			(layer "F.Fab")
		)
		(fp_line
			(start -0.12065 0.3048)
			(end -0.67945 0.3048)
			(stroke
				(width 0.1)
				(type default)
			)
			(layer "F.Fab")
		)
		(fp_line
			(start 0.120396 0.3048)
			(end 0.120396 0.2794)
			(stroke
				(width 0.1)
				(type default)
			)
			(layer "F.Fab")
		)
		(fp_line
			(start 0.67945 0.3048)
			(end 0.120396 0.3048)
			(stroke
				(width 0.1)
				(type default)
			)
			(layer "F.Fab")
		)
		(fp_line
			(start -0.12065 0.2794)
			(end -0.12065 0.3048)
			(stroke
				(width 0.1)
				(type default)
			)
			(layer "F.Fab")
		)
		(fp_line
			(start 0.120396 0.2794)
			(end -0.12065 0.2794)
			(stroke
				(width 0.1)
				(type default)
			)
			(layer "F.Fab")
		)
		(fp_line
			(start -0.12065 -0.2794)
			(end 0.12065 -0.2794)
			(stroke
				(width 0.1)
				(type default)
			)
			(layer "F.Fab")
		)
		(fp_line
			(start 0.12065 -0.2794)
			(end 0.12065 -0.3048)
			(stroke
				(width 0.1)
				(type default)
			)
			(layer "F.Fab")
		)
		(fp_line
			(start 0.12065 -0.3048)
			(end 0.67945 -0.3048)
			(stroke
				(width 0.1)
				(type default)
			)
			(layer "F.Fab")
		)
		(fp_line
			(start 0.67945 -0.3048)
			(end 0.67945 0.3048)
			(stroke
				(width 0.1)
				(type default)
			)
			(layer "F.Fab")
		)
		(fp_line
			(start -0.67945 -0.305054)
			(end -0.12065 -0.305054)
			(stroke
				(width 0.1)
				(type default)
			)
			(layer "F.Fab")
		)
		(fp_line
			(start -0.12065 -0.305054)
			(end -0.12065 -0.2794)
			(stroke
				(width 0.1)
				(type default)
			)
			(layer "F.Fab")
		)
		(pad "1" smd circle
			(at -0.40005 0 270)
			(size 0 0)
			(layers "F.Cu" "F.Mask" "F.Paste")
			(net "RST_USB_HUB_N")
		)
		(pad "2" smd circle
			(at 0.40005 0 270)
			(size 0 0)
			(layers "F.Cu" "F.Mask" "F.Paste")
			(net "USB_HUB2_MRP_RESET_N")
		)
	)
	(footprint ""
		(layer "F.Cu")
		(at 365.887 -413.639 90)
		(property "Reference" "R4183"
			(at 0 0 90)
			(layer "F.SilkS")
			(hide yes)
			(effects
				(font
					(size 1.27 1.27)
				)
			)
		)
		(property "Value" ""
			(at 0 0 90)
			(layer "F.Fab")
			(effects
				(font
					(size 1.27 1.27)
				)
			)
		)
		(duplicate_pad_numbers_are_jumpers no)
		(fp_line
			(start 0.7874 -0.4064)
			(end 0.7874 0.4064)
			(stroke
				(width 0.1524)
				(type default)
			)
			(layer "F.SilkS")
		)
		(fp_line
			(start -0.7874 -0.4064)
			(end 0.7874 -0.4064)
			(stroke
				(width 0.1524)
				(type default)
			)
			(layer "F.SilkS")
		)
		(fp_line
			(start 0.7874 0.4064)
			(end -0.7874 0.4064)
			(stroke
				(width 0.1524)
				(type default)
			)
			(layer "F.SilkS")
		)
		(fp_line
			(start -0.7874 0.4064)
			(end -0.7874 -0.4064)
			(stroke
				(width 0.1524)
				(type default)
			)
			(layer "F.SilkS")
		)
		(fp_line
			(start -0.12065 -0.305054)
			(end -0.12065 -0.2794)
			(stroke
				(width 0.1)
				(type default)
			)
			(layer "F.Fab")
		)
		(fp_line
			(start -0.67945 -0.305054)
			(end -0.12065 -0.305054)
			(stroke
				(width 0.1)
				(type default)
			)
			(layer "F.Fab")
		)
		(fp_line
			(start 0.67945 -0.3048)
			(end 0.67945 0.3048)
			(stroke
				(width 0.1)
				(type default)
			)
			(layer "F.Fab")
		)
		(fp_line
			(start 0.12065 -0.3048)
			(end 0.67945 -0.3048)
			(stroke
				(width 0.1)
				(type default)
			)
			(layer "F.Fab")
		)
		(fp_line
			(start 0.12065 -0.2794)
			(end 0.12065 -0.3048)
			(stroke
				(width 0.1)
				(type default)
			)
			(layer "F.Fab")
		)
		(fp_line
			(start -0.12065 -0.2794)
			(end 0.12065 -0.2794)
			(stroke
				(width 0.1)
				(type default)
			)
			(layer "F.Fab")
		)
		(fp_line
			(start 0.120396 0.2794)
			(end -0.12065 0.2794)
			(stroke
				(width 0.1)
				(type default)
			)
			(layer "F.Fab")
		)
		(fp_line
			(start -0.12065 0.2794)
			(end -0.12065 0.3048)
			(stroke
				(width 0.1)
				(type default)
			)
			(layer "F.Fab")
		)
		(fp_line
			(start 0.67945 0.3048)
			(end 0.120396 0.3048)
			(stroke
				(width 0.1)
				(type default)
			)
			(layer "F.Fab")
		)
		(fp_line
			(start 0.120396 0.3048)
			(end 0.120396 0.2794)
			(stroke
				(width 0.1)
				(type default)
			)
			(layer "F.Fab")
		)
		(fp_line
			(start -0.12065 0.3048)
			(end -0.67945 0.3048)
			(stroke
				(width 0.1)
				(type default)
			)
			(layer "F.Fab")
		)
		(fp_line
			(start -0.67945 0.3048)
			(end -0.67945 -0.305054)
			(stroke
				(width 0.1)
				(type default)
			)
			(layer "F.Fab")
		)
		(pad "1" smd circle
			(at -0.40005 0 90)
			(size 0 0)
			(layers "F.Cu" "F.Mask" "F.Paste")
			(net "SMB_LM75_0_3V3AUX_SDA")
		)
		(pad "2" smd circle
			(at 0.40005 0 90)
			(size 0 0)
			(layers "F.Cu" "F.Mask" "F.Paste")
			(net "SMB_LM75_0_3V3AUX_SDA_R1")
		)
	)
	(footprint ""
		(layer "F.Cu")
		(at 20.981924 -407.976578 90)
		(property "Reference" "R662"
			(at 0 0 90)
			(layer "F.SilkS")
			(hide yes)
			(effects
				(font
					(size 1.27 1.27)
				)
			)
		)
		(property "Value" ""
			(at 0 0 90)
			(layer "F.Fab")
			(effects
				(font
					(size 1.27 1.27)
				)
			)
		)
		(duplicate_pad_numbers_are_jumpers no)
		(fp_line
			(start 0.7874 -0.4064)
			(end 0.7874 0.4064)
			(stroke
				(width 0.1524)
				(type default)
			)
			(layer "F.SilkS")
		)
		(fp_line
			(start -0.7874 -0.4064)
			(end 0.7874 -0.4064)
			(stroke
				(width 0.1524)
				(type default)
			)
			(layer "F.SilkS")
		)
		(fp_line
			(start 0.7874 0.4064)
			(end -0.7874 0.4064)
			(stroke
				(width 0.1524)
				(type default)
			)
			(layer "F.SilkS")
		)
		(fp_line
			(start -0.7874 0.4064)
			(end -0.7874 -0.4064)
			(stroke
				(width 0.1524)
				(type default)
			)
			(layer "F.SilkS")
		)
		(fp_line
			(start -0.12065 -0.305054)
			(end -0.12065 -0.2794)
			(stroke
				(width 0.1)
				(type default)
			)
			(layer "F.Fab")
		)
		(fp_line
			(start -0.67945 -0.305054)
			(end -0.12065 -0.305054)
			(stroke
				(width 0.1)
				(type default)
			)
			(layer "F.Fab")
		)
		(fp_line
			(start 0.67945 -0.3048)
			(end 0.67945 0.3048)
			(stroke
				(width 0.1)
				(type default)
			)
			(layer "F.Fab")
		)
		(fp_line
			(start 0.12065 -0.3048)
			(end 0.67945 -0.3048)
			(stroke
				(width 0.1)
				(type default)
			)
			(layer "F.Fab")
		)
		(fp_line
			(start 0.12065 -0.2794)
			(end 0.12065 -0.3048)
			(stroke
				(width 0.1)
				(type default)
			)
			(layer "F.Fab")
		)
		(fp_line
			(start -0.12065 -0.2794)
			(end 0.12065 -0.2794)
			(stroke
				(width 0.1)
				(type default)
			)
			(layer "F.Fab")
		)
		(fp_line
			(start 0.120396 0.2794)
			(end -0.12065 0.2794)
			(stroke
				(width 0.1)
				(type default)
			)
			(layer "F.Fab")
		)
		(fp_line
			(start -0.12065 0.2794)
			(end -0.12065 0.3048)
			(stroke
				(width 0.1)
				(type default)
			)
			(layer "F.Fab")
		)
		(fp_line
			(start 0.67945 0.3048)
			(end 0.120396 0.3048)
			(stroke
				(width 0.1)
				(type default)
			)
			(layer "F.Fab")
		)
		(fp_line
			(start 0.120396 0.3048)
			(end 0.120396 0.2794)
			(stroke
				(width 0.1)
				(type default)
			)
			(layer "F.Fab")
		)
		(fp_line
			(start -0.12065 0.3048)
			(end -0.67945 0.3048)
			(stroke
				(width 0.1)
				(type default)
			)
			(layer "F.Fab")
		)
		(fp_line
			(start -0.67945 0.3048)
			(end -0.67945 -0.305054)
			(stroke
				(width 0.1)
				(type default)
			)
			(layer "F.Fab")
		)
		(pad "1" smd circle
			(at -0.40005 0 90)
			(size 0 0)
			(layers "F.Cu" "F.Mask" "F.Paste")
			(net "P0V9_RETIMER_CPU1_EN")
		)
		(pad "2" smd circle
			(at 0.40005 0 90)
			(size 0 0)
			(layers "F.Cu" "F.Mask" "F.Paste")
			(net "P0V9_RETIMER_CPU1_EN0_R")
		)
	)
	(footprint ""
		(layer "F.Cu")
		(at 436.224172 -32.173418 90)
		(property "Reference" "R3872"
			(at 0 0 90)
			(layer "F.SilkS")
			(hide yes)
			(effects
				(font
					(size 1.27 1.27)
				)
			)
		)
		(property "Value" ""
			(at 0 0 90)
			(layer "F.Fab")
			(effects
				(font
					(size 1.27 1.27)
				)
			)
		)
		(duplicate_pad_numbers_are_jumpers no)
		(fp_line
			(start 0.7874 -0.4064)
			(end 0.7874 0.4064)
			(stroke
				(width 0.1524)
				(type default)
			)
			(layer "F.SilkS")
		)
		(fp_line
			(start -0.7874 -0.4064)
			(end 0.7874 -0.4064)
			(stroke
				(width 0.1524)
				(type default)
			)
			(layer "F.SilkS")
		)
		(fp_line
			(start 0.7874 0.4064)
			(end -0.7874 0.4064)
			(stroke
				(width 0.1524)
				(type default)
			)
			(layer "F.SilkS")
		)
		(fp_line
			(start -0.7874 0.4064)
			(end -0.7874 -0.4064)
			(stroke
				(width 0.1524)
				(type default)
			)
			(layer "F.SilkS")
		)
		(fp_line
			(start -0.12065 -0.305054)
			(end -0.12065 -0.2794)
			(stroke
				(width 0.1)
				(type default)
			)
			(layer "F.Fab")
		)
		(fp_line
			(start -0.67945 -0.305054)
			(end -0.12065 -0.305054)
			(stroke
				(width 0.1)
				(type default)
			)
			(layer "F.Fab")
		)
		(fp_line
			(start 0.67945 -0.3048)
			(end 0.67945 0.3048)
			(stroke
				(width 0.1)
				(type default)
			)
			(layer "F.Fab")
		)
		(fp_line
			(start 0.12065 -0.3048)
			(end 0.67945 -0.3048)
			(stroke
				(width 0.1)
				(type default)
			)
			(layer "F.Fab")
		)
		(fp_line
			(start 0.12065 -0.2794)
			(end 0.12065 -0.3048)
			(stroke
				(width 0.1)
				(type default)
			)
			(layer "F.Fab")
		)
		(fp_line
			(start -0.12065 -0.2794)
			(end 0.12065 -0.2794)
			(stroke
				(width 0.1)
				(type default)
			)
			(layer "F.Fab")
		)
		(fp_line
			(start 0.120396 0.2794)
			(end -0.12065 0.2794)
			(stroke
				(width 0.1)
				(type default)
			)
			(layer "F.Fab")
		)
		(fp_line
			(start -0.12065 0.2794)
			(end -0.12065 0.3048)
			(stroke
				(width 0.1)
				(type default)
			)
			(layer "F.Fab")
		)
		(fp_line
			(start 0.67945 0.3048)
			(end 0.120396 0.3048)
			(stroke
				(width 0.1)
				(type default)
			)
			(layer "F.Fab")
		)
		(fp_line
			(start 0.120396 0.3048)
			(end 0.120396 0.2794)
			(stroke
				(width 0.1)
				(type default)
			)
			(layer "F.Fab")
		)
		(fp_line
			(start -0.12065 0.3048)
			(end -0.67945 0.3048)
			(stroke
				(width 0.1)
				(type default)
			)
			(layer "F.Fab")
		)
		(fp_line
			(start -0.67945 0.3048)
			(end -0.67945 -0.305054)
			(stroke
				(width 0.1)
				(type default)
			)
			(layer "F.Fab")
		)
		(pad "1" smd circle
			(at -0.40005 0 90)
			(size 0 0)
			(layers "F.Cu" "F.Mask" "F.Paste")
			(net "P12V_OCP_IMON_1")
		)
		(pad "2" smd circle
			(at 0.40005 0 90)
			(size 0 0)
			(layers "F.Cu" "F.Mask" "F.Paste")
			(net "P12V_OCP_SFF_ISENSE_MPS_TIC")
		)
	)
	(footprint ""
		(layer "F.Cu")
		(at 428.276766 -348.135956 180)
		(property "Reference" "PC168"
			(at 0 0 180)
			(layer "F.SilkS")
			(hide yes)
			(effects
				(font
					(size 1.27 1.27)
				)
			)
		)
		(property "Value" ""
			(at 0 0 180)
			(layer "F.Fab")
			(effects
				(font
					(size 1.27 1.27)
				)
			)
		)
		(duplicate_pad_numbers_are_jumpers no)
		(fp_line
			(start 0.7874 0.4064)
			(end -0.7874 0.4064)
			(stroke
				(width 0.1524)
				(type default)
			)
			(layer "F.SilkS")
		)
		(fp_line
			(start 0.7874 -0.4064)
			(end 0.7874 0.4064)
			(stroke
				(width 0.1524)
				(type default)
			)
			(layer "F.SilkS")
		)
		(fp_line
			(start -0.7874 0.4064)
			(end -0.7874 -0.4064)
			(stroke
				(width 0.1524)
				(type default)
			)
			(layer "F.SilkS")
		)
		(fp_line
			(start -0.7874 -0.4064)
			(end 0.7874 -0.4064)
			(stroke
				(width 0.1524)
				(type default)
			)
			(layer "F.SilkS")
		)
		(fp_line
			(start 0.67945 0.3048)
			(end 0.120396 0.3048)
			(stroke
				(width 0.1)
				(type default)
			)
			(layer "F.Fab")
		)
		(fp_line
			(start 0.67945 -0.3048)
			(end 0.67945 0.3048)
			(stroke
				(width 0.1)
				(type default)
			)
			(layer "F.Fab")
		)
		(fp_line
			(start 0.12065 -0.2794)
			(end 0.12065 -0.3048)
			(stroke
				(width 0.1)
				(type default)
			)
			(layer "F.Fab")
		)
		(fp_line
			(start 0.12065 -0.3048)
			(end 0.67945 -0.3048)
			(stroke
				(width 0.1)
				(type default)
			)
			(layer "F.Fab")
		)
		(fp_line
			(start 0.120396 0.3048)
			(end 0.120396 0.2794)
			(stroke
				(width 0.1)
				(type default)
			)
			(layer "F.Fab")
		)
		(fp_line
			(start 0.120396 0.2794)
			(end -0.12065 0.2794)
			(stroke
				(width 0.1)
				(type default)
			)
			(layer "F.Fab")
		)
		(fp_line
			(start -0.12065 0.3048)
			(end -0.67945 0.3048)
			(stroke
				(width 0.1)
				(type default)
			)
			(layer "F.Fab")
		)
		(fp_line
			(start -0.12065 0.2794)
			(end -0.12065 0.3048)
			(stroke
				(width 0.1)
				(type default)
			)
			(layer "F.Fab")
		)
		(fp_line
			(start -0.12065 -0.2794)
			(end 0.12065 -0.2794)
			(stroke
				(width 0.1)
				(type default)
			)
			(layer "F.Fab")
		)
		(fp_line
			(start -0.12065 -0.305054)
			(end -0.12065 -0.2794)
			(stroke
				(width 0.1)
				(type default)
			)
			(layer "F.Fab")
		)
		(fp_line
			(start -0.67945 0.3048)
			(end -0.67945 -0.305054)
			(stroke
				(width 0.1)
				(type default)
			)
			(layer "F.Fab")
		)
		(fp_line
			(start -0.67945 -0.305054)
			(end -0.12065 -0.305054)
			(stroke
				(width 0.1)
				(type default)
			)
			(layer "F.Fab")
		)
		(pad "1" smd circle
			(at -0.40005 0 180)
			(size 0 0)
			(layers "F.Cu" "F.Mask" "F.Paste")
			(net "SW_PVDD11_S3_P0_SW2")
		)
		(pad "2" smd circle
			(at 0.40005 0 180)
			(size 0 0)
			(layers "F.Cu" "F.Mask" "F.Paste")
			(net "SW_PVDD11_S3_P0_SW2_RC")
		)
	)
	(footprint ""
		(layer "F.Cu")
		(at 255.37033 -55.860442 90)
		(property "Reference" "PR3951"
			(at 0 0 90)
			(layer "F.SilkS")
			(hide yes)
			(effects
				(font
					(size 1.27 1.27)
				)
			)
		)
		(property "Value" ""
			(at 0 0 90)
			(layer "F.Fab")
			(effects
				(font
					(size 1.27 1.27)
				)
			)
		)
		(duplicate_pad_numbers_are_jumpers no)
		(fp_line
			(start 0.7874 -0.4064)
			(end 0.7874 0.4064)
			(stroke
				(width 0.1524)
				(type default)
			)
			(layer "F.SilkS")
		)
		(fp_line
			(start -0.7874 -0.4064)
			(end 0.7874 -0.4064)
			(stroke
				(width 0.1524)
				(type default)
			)
			(layer "F.SilkS")
		)
		(fp_line
			(start 0.7874 0.4064)
			(end -0.7874 0.4064)
			(stroke
				(width 0.1524)
				(type default)
			)
			(layer "F.SilkS")
		)
		(fp_line
			(start -0.7874 0.4064)
			(end -0.7874 -0.4064)
			(stroke
				(width 0.1524)
				(type default)
			)
			(layer "F.SilkS")
		)
		(fp_line
			(start -0.12065 -0.305054)
			(end -0.12065 -0.2794)
			(stroke
				(width 0.1)
				(type default)
			)
			(layer "F.Fab")
		)
		(fp_line
			(start -0.67945 -0.305054)
			(end -0.12065 -0.305054)
			(stroke
				(width 0.1)
				(type default)
			)
			(layer "F.Fab")
		)
		(fp_line
			(start 0.67945 -0.3048)
			(end 0.67945 0.3048)
			(stroke
				(width 0.1)
				(type default)
			)
			(layer "F.Fab")
		)
		(fp_line
			(start 0.12065 -0.3048)
			(end 0.67945 -0.3048)
			(stroke
				(width 0.1)
				(type default)
			)
			(layer "F.Fab")
		)
		(fp_line
			(start 0.12065 -0.2794)
			(end 0.12065 -0.3048)
			(stroke
				(width 0.1)
				(type default)
			)
			(layer "F.Fab")
		)
		(fp_line
			(start -0.12065 -0.2794)
			(end 0.12065 -0.2794)
			(stroke
				(width 0.1)
				(type default)
			)
			(layer "F.Fab")
		)
		(fp_line
			(start 0.120396 0.2794)
			(end -0.12065 0.2794)
			(stroke
				(width 0.1)
				(type default)
			)
			(layer "F.Fab")
		)
		(fp_line
			(start -0.12065 0.2794)
			(end -0.12065 0.3048)
			(stroke
				(width 0.1)
				(type default)
			)
			(layer "F.Fab")
		)
		(fp_line
			(start 0.67945 0.3048)
			(end 0.120396 0.3048)
			(stroke
				(width 0.1)
				(type default)
			)
			(layer "F.Fab")
		)
		(fp_line
			(start 0.120396 0.3048)
			(end 0.120396 0.2794)
			(stroke
				(width 0.1)
				(type default)
			)
			(layer "F.Fab")
		)
		(fp_line
			(start -0.12065 0.3048)
			(end -0.67945 0.3048)
			(stroke
				(width 0.1)
				(type default)
			)
			(layer "F.Fab")
		)
		(fp_line
			(start -0.67945 0.3048)
			(end -0.67945 -0.305054)
			(stroke
				(width 0.1)
				(type default)
			)
			(layer "F.Fab")
		)
		(pad "1" smd circle
			(at -0.40005 0 90)
			(size 0 0)
			(layers "F.Cu" "F.Mask" "F.Paste")
			(net "P12V_E1S_FLTB_0")
		)
		(pad "2" smd circle
			(at 0.40005 0 90)
			(size 0 0)
			(layers "F.Cu" "F.Mask" "F.Paste")
			(net "P3V3_AUX")
		)
	)
)
